(kicad_pcb
	(version 20221018)
	(generator pcbnew)
	(general
    (thickness 1.62)
  )
	(paper "A4")
	(title_block
    (title "ECP5 - Datacenter Secure Control Module (DC-SCM)")
    (date "2024-07-01")
    (rev "1.2.1")
		(comment 9 "footprints 467-473 of 506")
	)
	(layers
    (0 "F.Cu" signal)
    (1 "In1.Cu" power)
    (2 "In2.Cu" signal)
    (3 "In3.Cu" power)
    (4 "In4.Cu" power)
    (5 "In5.Cu" signal)
    (6 "In6.Cu" power)
    (31 "B.Cu" signal)
    (32 "B.Adhes" user "B.Adhesive")
    (33 "F.Adhes" user "F.Adhesive")
    (34 "B.Paste" user)
    (35 "F.Paste" user)
    (36 "B.SilkS" user "B.Silkscreen")
    (37 "F.SilkS" user "F.Silkscreen")
    (38 "B.Mask" user)
    (39 "F.Mask" user)
    (40 "Dwgs.User" user "User.Drawings")
    (41 "Cmts.User" user "User.Comments")
    (42 "Eco1.User" user "User.Eco1")
    (43 "Eco2.User" user "User.Eco2")
    (44 "Edge.Cuts" user)
    (45 "Margin" user)
    (46 "B.CrtYd" user "B.Courtyard")
    (47 "F.CrtYd" user "F.Courtyard")
    (48 "B.Fab" user)
    (49 "F.Fab" user)
  )
	(footprint "antmicro-footprints:SOT-23-3" (layer "B.Cu")
    (at 71.2 85.05)
    (property "Author" "Antmicro")
    (property "License" "Apache-2.0")
    (property "MPN" "2N7002")
    (property "Manufacturer" "ON Semiconductor")
    (property "Sheetfile" "power-supply.kicad_sch")
    (property "Sheetname" "Power supply")
    (property "ki_description" "Power MOSFET, N Channel, 60 V, 115 mA, 1.2 ohm, SOT-23, Surface Mount")
    (property "ki_keywords" "SMT, TRANSISTOR, SEMICONDUCTOR, NMOS")
    (attr smd)
    (fp_text reference "Q10" (at 0 -2.45 180) (layer "B.SilkS")
        (effects (font (size 0.7 0.7) (thickness 0.127)) (justify mirror))
    )
    (fp_text value "2N7002" (at 0.025 -3.25) (layer "B.Fab")
        (effects (font (size 1 1) (thickness 0.15)) (justify mirror))
    )
    (fp_text user "Author: Antmicro" (at -1.837 -5.3 180) (layer "B.Fab") hide
        (effects (font (size 0.7 0.7) (thickness 0.15)) (justify left bottom mirror))
    )
    (fp_text user "${REFERENCE}" (at -0.125 -0.15) (layer "B.Fab")
        (effects (font (size 0.25 0.25) (thickness 0.05)) (justify mirror))
    )
    (fp_text user "License: Apache-2.0" (at -1.8 -6.8 180) (layer "B.Fab") hide
        (effects (font (size 0.7 0.7) (thickness 0.15)) (justify left bottom mirror))
    )
    (fp_line (start -1.45 1.35) (end -0.85 1.35)
      (stroke (width 0.15) (type solid)) (layer "B.SilkS"))
    (fp_line (start -0.85 1.35) (end -0.7 1.5)
      (stroke (width 0.15) (type solid)) (layer "B.SilkS"))
    (fp_line (start -0.7 -1.5) (end -0.7 -1.35)
      (stroke (width 0.15) (type solid)) (layer "B.SilkS"))
    (fp_line (start 0.7 -1.5) (end -0.7 -1.5)
      (stroke (width 0.15) (type solid)) (layer "B.SilkS"))
    (fp_line (start 0.7 -0.4) (end 0.7 -1.5)
      (stroke (width 0.15) (type solid)) (layer "B.SilkS"))
    (fp_line (start 0.7 0.4) (end 0.7 1.5)
      (stroke (width 0.15) (type solid)) (layer "B.SilkS"))
    (fp_line (start 0.7 1.5) (end -0.7 1.5)
      (stroke (width 0.15) (type solid)) (layer "B.SilkS"))
    (fp_line (start -1.75 -1.4) (end -1.75 -0.5)
      (stroke (width 0.05) (type solid)) (layer "B.CrtYd"))
    (fp_line (start -1.75 -0.5) (end -0.85 -0.5)
      (stroke (width 0.05) (type solid)) (layer "B.CrtYd"))
    (fp_line (start -1.75 0.5) (end -1.75 1.4)
      (stroke (width 0.05) (type solid)) (layer "B.CrtYd"))
    (fp_line (start -0.9 1.4) (end -1.75 1.4)
      (stroke (width 0.05) (type solid)) (layer "B.CrtYd"))
    (fp_line (start -0.9 1.6) (end -0.9 1.4)
      (stroke (width 0.05) (type solid)) (layer "B.CrtYd"))
    (fp_line (start -0.9 1.6) (end 0.825 1.6)
      (stroke (width 0.05) (type solid)) (layer "B.CrtYd"))
    (fp_line (start -0.85 -1.65) (end -0.85 -1.4)
      (stroke (width 0.05) (type solid)) (layer "B.CrtYd"))
    (fp_line (start -0.85 -1.4) (end -1.75 -1.4)
      (stroke (width 0.05) (type solid)) (layer "B.CrtYd"))
    (fp_line (start -0.85 -0.5) (end -0.85 0.5)
      (stroke (width 0.05) (type solid)) (layer "B.CrtYd"))
    (fp_line (start -0.85 0.5) (end -1.75 0.5)
      (stroke (width 0.05) (type solid)) (layer "B.CrtYd"))
    (fp_line (start 0.825 0.45) (end 1.75 0.45)
      (stroke (width 0.05) (type solid)) (layer "B.CrtYd"))
    (fp_line (start 0.825 1.6) (end 0.825 0.45)
      (stroke (width 0.05) (type solid)) (layer "B.CrtYd"))
    (fp_line (start 0.85 -1.65) (end -0.85 -1.65)
      (stroke (width 0.05) (type solid)) (layer "B.CrtYd"))
    (fp_line (start 0.85 -0.45) (end 0.85 -1.65)
      (stroke (width 0.05) (type solid)) (layer "B.CrtYd"))
    (fp_line (start 1.75 -0.45) (end 0.85 -0.45)
      (stroke (width 0.05) (type solid)) (layer "B.CrtYd"))
    (fp_line (start 1.75 0.45) (end 1.75 -0.45)
      (stroke (width 0.05) (type solid)) (layer "B.CrtYd"))
    (fp_line (start -0.712 -1.519) (end 0.688 -1.519)
      (stroke (width 0.15) (type solid)) (layer "B.Fab"))
    (fp_line (start -0.712 1.325) (end -0.712 -1.523)
      (stroke (width 0.15) (type solid)) (layer "B.Fab"))
    (fp_line (start -0.437 1.526) (end -0.712 1.325)
      (stroke (width 0.15) (type solid)) (layer "B.Fab"))
    (fp_line (start -0.437 1.526) (end 0.688 1.526)
      (stroke (width 0.15) (type solid)) (layer "B.Fab"))
    (fp_line (start 0.688 -1.519) (end 0.688 1.52)
      (stroke (width 0.15) (type solid)) (layer "B.Fab"))
    (pad "1" smd roundrect (at -1.1 0.951) (size 1 0.6) (layers "B.Cu" "B.Paste" "B.Mask") (roundrect_rratio 0.15)
      (net 235 "/Power supply/1V2_PG") (pinfunction "G") (pintype "passive"))
    (pad "2" smd roundrect (at -1.1 -0.949) (size 1 0.6) (layers "B.Cu" "B.Paste" "B.Mask") (roundrect_rratio 0.15)
      (net 1 "GND") (pinfunction "S") (pintype "passive"))
    (pad "3" smd roundrect (at 1.1 0.0005) (size 1 0.6) (layers "B.Cu" "B.Paste" "B.Mask") (roundrect_rratio 0.15)
      (net 394 "Net-(Q10-D)") (pinfunction "D") (pintype "passive"))
  )
	(footprint "antmicro-footprints:C_0402_1005Metric" (layer "B.Cu")
    (at 82.65 120.5 180)
    (descr "Capacitor SMD 0402")
    (tags "capacitor SMD 0402")
    (property "Author" "Antmicro")
    (property "Dielectric" "X5R")
    (property "License" "Apache-2.0")
    (property "MPN" "GRM155R61H104KE14D")
    (property "Manufacturer" "Murata")
    (property "Public" "False")
    (property "Sheetfile" "ddr3.kicad_sch")
    (property "Sheetname" "DDR3")
    (property "Val" "100n")
    (property "Voltage" "50V")
    (property "ki_description" "SMD Multilayer Ceramic Capacitor, 0.1 µF, 50 V, 0402 [1005 Metric], ± 10%, X5R, GRM Series")
    (property "ki_keywords" "0402, SMT, CAPACITOR, PASSIVE, CERAMIC, MLCC")
    (attr smd)
    (fp_text reference "C93" (at 0 1.17) (layer "B.SilkS")
        (effects (font (size 0.7 0.7) (thickness 0.127)) (justify mirror))
    )
    (fp_text value "C_100n_0402" (at 0 -1.17) (layer "B.Fab")
        (effects (font (size 1 1) (thickness 0.15)) (justify mirror))
    )
    (fp_text user "License: Apache-2.0" (at -0.939 -5.799) (layer "B.Fab") hide
        (effects (font (size 0.7 0.7) (thickness 0.15)) (justify left bottom mirror))
    )
    (fp_text user "${REFERENCE}" (at 0 0) (layer "B.Fab")
        (effects (font (size 0.25 0.25) (thickness 0.04)) (justify mirror))
    )
    (fp_text user "Author: Antmicro" (at -0.939 -3.399) (layer "B.Fab") hide
        (effects (font (size 0.7 0.7) (thickness 0.15)) (justify left bottom mirror))
    )
    (fp_rect (start -0.925 0.47) (end 0.925 -0.47)
      (stroke (width 0.05) (type default)) (fill none) (layer "B.CrtYd"))
    (fp_line (start -0.494 -0.248) (end -0.494 0.25)
      (stroke (width 0.15) (type solid)) (layer "B.Fab"))
    (fp_line (start -0.494 0.25) (end 0.504 0.25)
      (stroke (width 0.15) (type solid)) (layer "B.Fab"))
    (fp_line (start 0.504 -0.248) (end -0.494 -0.248)
      (stroke (width 0.15) (type solid)) (layer "B.Fab"))
    (fp_line (start 0.504 0.25) (end 0.504 -0.248)
      (stroke (width 0.15) (type solid)) (layer "B.Fab"))
    (pad "1" smd roundrect (at -0.48 0 180) (size 0.59 0.64) (layers "B.Cu" "B.Paste" "B.Mask") (roundrect_rratio 0.25)
      (net 1 "GND") (pintype "passive"))
    (pad "2" smd roundrect (at 0.48 0 180) (size 0.59 0.64) (layers "B.Cu" "B.Paste" "B.Mask") (roundrect_rratio 0.25)
      (net 217 "DDR3_VREF") (pintype "passive"))
  )
	(footprint "antmicro-footprints:C_0402_1005Metric" (layer "B.Cu")
    (at 91.7 122.15 180)
    (descr "Capacitor SMD 0402")
    (tags "capacitor SMD 0402")
    (property "Author" "Antmicro")
    (property "Dielectric" "X5R")
    (property "License" "Apache-2.0")
    (property "MPN" "GRM155R61H104KE14D")
    (property "Manufacturer" "Murata")
    (property "Public" "False")
    (property "Sheetfile" "fpga-banks.kicad_sch")
    (property "Sheetname" "FPGA banks")
    (property "Val" "100n")
    (property "Voltage" "50V")
    (property "ki_description" "SMD Multilayer Ceramic Capacitor, 0.1 µF, 50 V, 0402 [1005 Metric], ± 10%, X5R, GRM Series")
    (property "ki_keywords" "0402, SMT, CAPACITOR, PASSIVE, CERAMIC, MLCC")
    (attr smd)
    (fp_text reference "C216" (at 0.02 0.885 180) (layer "B.SilkS")
        (effects (font (size 0.7 0.7) (thickness 0.127)) (justify mirror))
    )
    (fp_text value "C_100n_0402" (at 0 -1.17 180) (layer "B.Fab")
        (effects (font (size 1 1) (thickness 0.15)) (justify mirror))
    )
    (fp_text user "${REFERENCE}" (at 0 0 180) (layer "B.Fab")
        (effects (font (size 0.25 0.25) (thickness 0.04)) (justify mirror))
    )
    (fp_text user "Author: Antmicro" (at -0.939 -3.399) (layer "B.Fab") hide
        (effects (font (size 0.7 0.7) (thickness 0.15)) (justify left bottom mirror))
    )
    (fp_text user "License: Apache-2.0" (at -0.939 -5.799) (layer "B.Fab") hide
        (effects (font (size 0.7 0.7) (thickness 0.15)) (justify left bottom mirror))
    )
    (fp_rect (start -0.925 0.47) (end 0.925 -0.47)
      (stroke (width 0.05) (type default)) (fill none) (layer "B.CrtYd"))
    (fp_line (start -0.494 -0.248) (end -0.494 0.25)
      (stroke (width 0.15) (type solid)) (layer "B.Fab"))
    (fp_line (start -0.494 0.25) (end 0.504 0.25)
      (stroke (width 0.15) (type solid)) (layer "B.Fab"))
    (fp_line (start 0.504 -0.248) (end -0.494 -0.248)
      (stroke (width 0.15) (type solid)) (layer "B.Fab"))
    (fp_line (start 0.504 0.25) (end 0.504 -0.248)
      (stroke (width 0.15) (type solid)) (layer "B.Fab"))
    (pad "1" smd roundrect (at -0.48 0 180) (size 0.59 0.64) (layers "B.Cu" "B.Paste" "B.Mask") (roundrect_rratio 0.25)
      (net 1 "GND") (pintype "passive"))
    (pad "2" smd roundrect (at 0.48 0 180) (size 0.59 0.64) (layers "B.Cu" "B.Paste" "B.Mask") (roundrect_rratio 0.25)
      (net 217 "DDR3_VREF") (pintype "passive"))
  )
	(footprint "antmicro-footprints:C_0402_1005Metric" (layer "B.Cu")
    (at 93.6 122.95)
    (descr "Capacitor SMD 0402")
    (tags "capacitor SMD 0402")
    (property "Author" "Antmicro")
    (property "Dielectric" "X5R")
    (property "License" "Apache-2.0")
    (property "MPN" "GRM155R61H104KE14D")
    (property "Manufacturer" "Murata")
    (property "Public" "False")
    (property "Sheetfile" "fpga-banks.kicad_sch")
    (property "Sheetname" "FPGA banks")
    (property "Val" "100n")
    (property "Voltage" "50V")
    (property "ki_description" "SMD Multilayer Ceramic Capacitor, 0.1 µF, 50 V, 0402 [1005 Metric], ± 10%, X5R, GRM Series")
    (property "ki_keywords" "0402, SMT, CAPACITOR, PASSIVE, CERAMIC, MLCC")
    (attr smd)
    (fp_text reference "C217" (at -1.35 0.95) (layer "B.SilkS")
        (effects (font (size 0.7 0.7) (thickness 0.127)) (justify mirror))
    )
    (fp_text value "C_100n_0402" (at 0 -1.17) (layer "B.Fab")
        (effects (font (size 1 1) (thickness 0.15)) (justify mirror))
    )
    (fp_text user "Author: Antmicro" (at -0.939 -3.399 180) (layer "B.Fab") hide
        (effects (font (size 0.7 0.7) (thickness 0.15)) (justify left bottom mirror))
    )
    (fp_text user "License: Apache-2.0" (at -0.939 -5.799 180) (layer "B.Fab") hide
        (effects (font (size 0.7 0.7) (thickness 0.15)) (justify left bottom mirror))
    )
    (fp_text user "${REFERENCE}" (at 0 0) (layer "B.Fab")
        (effects (font (size 0.25 0.25) (thickness 0.04)) (justify mirror))
    )
    (fp_rect (start -0.925 0.47) (end 0.925 -0.47)
      (stroke (width 0.05) (type default)) (fill none) (layer "B.CrtYd"))
    (fp_line (start -0.494 -0.248) (end -0.494 0.25)
      (stroke (width 0.15) (type solid)) (layer "B.Fab"))
    (fp_line (start -0.494 0.25) (end 0.504 0.25)
      (stroke (width 0.15) (type solid)) (layer "B.Fab"))
    (fp_line (start 0.504 -0.248) (end -0.494 -0.248)
      (stroke (width 0.15) (type solid)) (layer "B.Fab"))
    (fp_line (start 0.504 0.25) (end 0.504 -0.248)
      (stroke (width 0.15) (type solid)) (layer "B.Fab"))
    (pad "1" smd roundrect (at -0.48 0) (size 0.59 0.64) (layers "B.Cu" "B.Paste" "B.Mask") (roundrect_rratio 0.25)
      (net 1 "GND") (pintype "passive"))
    (pad "2" smd roundrect (at 0.48 0) (size 0.59 0.64) (layers "B.Cu" "B.Paste" "B.Mask") (roundrect_rratio 0.25)
      (net 217 "DDR3_VREF") (pintype "passive"))
  )
	(footprint "antmicro-footprints:R_0402_1005Metric" (layer "B.Cu")
    (at 94.575 96.075 180)
    (descr "Resistor SMD 0402")
    (tags "resistor SMD 0402")
    (property "Author" "Antmicro")
    (property "License" "Apache-2.0")
    (property "MPN" "CR0402-FX-4702GLF")
    (property "Manufacturer" "Bourns")
    (property "Public" "False")
    (property "Sheetfile" "interfaces.kicad_sch")
    (property "Sheetname" "Interfaces")
    (property "Tolerance" "1%")
    (property "Val" "47k")
    (property "ki_description" "SMD Chip Resistor, 47 kohm, ± 1%, 62.5 mW, 0402 [1005 Metric], Thick Film, General Purpose")
    (property "ki_keywords" "0402, SMT, RESISTOR, PASSIVE")
    (attr smd)
    (fp_text reference "R65" (at 0.025 -7.425) (layer "B.SilkS")
        (effects (font (size 0.7 0.7) (thickness 0.127)) (justify mirror))
    )
    (fp_text value "R_47k_0402" (at 0 -1.17) (layer "B.Fab")
        (effects (font (size 1 1) (thickness 0.15)) (justify mirror))
    )
    (fp_text user "Author: Antmicro" (at -0.95 -4.169) (layer "B.Fab") hide
        (effects (font (size 0.7 0.7) (thickness 0.15)) (justify left bottom mirror))
    )
    (fp_text user "${REFERENCE}" (at 0 0) (layer "B.Fab")
        (effects (font (size 0.25 0.25) (thickness 0.04)) (justify mirror))
    )
    (fp_text user "License: Apache-2.0" (at -0.95 -5.169) (layer "B.Fab") hide
        (effects (font (size 0.7 0.7) (thickness 0.15)) (justify left bottom mirror))
    )
    (fp_rect (start -0.925 0.47) (end 0.925 -0.47)
      (stroke (width 0.05) (type default)) (fill none) (layer "B.CrtYd"))
    (fp_rect (start -0.5 0.25) (end 0.5 -0.25)
      (stroke (width 0.15) (type solid)) (fill none) (layer "B.Fab"))
    (pad "1" smd roundrect (at -0.48 0 180) (size 0.59 0.64) (layers "B.Cu" "B.Paste" "B.Mask") (roundrect_rratio 0.25)
      (net 2 "VCC3V3") (pintype "passive"))
    (pad "2" smd roundrect (at 0.48 0 180) (size 0.59 0.64) (layers "B.Cu" "B.Paste" "B.Mask") (roundrect_rratio 0.25)
      (net 283 "MMC_DAT4") (pintype "passive"))
  )
	(footprint "antmicro-footprints:R_0402_1005Metric" (layer "B.Cu")
    (at 77.65 93.75 90)
    (descr "Resistor SMD 0402")
    (tags "resistor SMD 0402")
    (property "Author" "Antmicro")
    (property "License" "Apache-2.0")
    (property "MPN" "CR0402-FX-1002GLF")
    (property "Manufacturer" "Bourns")
    (property "Public" "False")
    (property "Sheetfile" "power-supply.kicad_sch")
    (property "Sheetname" "Power supply")
    (property "Tolerance" "1%")
    (property "Val" "10k")
    (property "ki_description" "SMD Chip Resistor, 10 kohm, ± 1%, 62.5 mW, 0402 [1005 Metric], Thick Film, General Purpose")
    (property "ki_keywords" "0402, SMT, RESISTOR, PASSIVE")
    (attr smd)
    (fp_text reference "R102" (at 0.05 1.05 270) (layer "B.SilkS")
        (effects (font (size 0.7 0.7) (thickness 0.127)) (justify mirror))
    )
    (fp_text value "R_10k_0402" (at 0 -1.17 270) (layer "B.Fab")
        (effects (font (size 1 1) (thickness 0.15)) (justify mirror))
    )
    (fp_text user "Author: Antmicro" (at -0.95 -4.169 270) (layer "B.Fab") hide
        (effects (font (size 0.7 0.7) (thickness 0.15)) (justify left bottom mirror))
    )
    (fp_text user "${REFERENCE}" (at 0 0 270) (layer "B.Fab")
        (effects (font (size 0.25 0.25) (thickness 0.04)) (justify mirror))
    )
    (fp_text user "License: Apache-2.0" (at -0.95 -5.169 270) (layer "B.Fab") hide
        (effects (font (size 0.7 0.7) (thickness 0.15)) (justify left bottom mirror))
    )
    (fp_rect (start -0.925 0.47) (end 0.925 -0.47)
      (stroke (width 0.05) (type default)) (fill none) (layer "B.CrtYd"))
    (fp_rect (start -0.5 0.25) (end 0.5 -0.25)
      (stroke (width 0.15) (type solid)) (fill none) (layer "B.Fab"))
    (pad "1" smd roundrect (at -0.48 0 90) (size 0.59 0.64) (layers "B.Cu" "B.Paste" "B.Mask") (roundrect_rratio 0.25)
      (net 2 "VCC3V3") (pintype "passive"))
    (pad "2" smd roundrect (at 0.48 0 90) (size 0.59 0.64) (layers "B.Cu" "B.Paste" "B.Mask") (roundrect_rratio 0.25)
      (net 385 "1V0_PG") (pintype "passive"))
  )
	(footprint "antmicro-footprints:R_0402_1005Metric" (layer "B.Cu")
    (at 94.55 99.15 180)
    (descr "Resistor SMD 0402")
    (tags "resistor SMD 0402")
    (property "Author" "Antmicro")
    (property "License" "Apache-2.0")
    (property "MPN" "CR0402-FX-4702GLF")
    (property "Manufacturer" "Bourns")
    (property "Public" "False")
    (property "Sheetfile" "interfaces.kicad_sch")
    (property "Sheetname" "Interfaces")
    (property "Tolerance" "1%")
    (property "Val" "47k")
    (property "ki_description" "SMD Chip Resistor, 47 kohm, ± 1%, 62.5 mW, 0402 [1005 Metric], Thick Film, General Purpose")
    (property "ki_keywords" "0402, SMT, RESISTOR, PASSIVE")
    (attr smd)
    (fp_text reference "R59" (at 0 -7.202) (layer "B.SilkS")
        (effects (font (size 0.7 0.7) (thickness 0.127)) (justify mirror))
    )
    (fp_text value "R_47k_0402" (at 0 -1.17) (layer "B.Fab")
        (effects (font (size 1 1) (thickness 0.15)) (justify mirror))
    )
    (fp_text user "Author: Antmicro" (at -0.95 -4.169) (layer "B.Fab") hide
        (effects (font (size 0.7 0.7) (thickness 0.15)) (justify left bottom mirror))
    )
    (fp_text user "License: Apache-2.0" (at -0.95 -5.169) (layer "B.Fab") hide
        (effects (font (size 0.7 0.7) (thickness 0.15)) (justify left bottom mirror))
    )
    (fp_text user "${REFERENCE}" (at 0 0) (layer "B.Fab")
        (effects (font (size 0.25 0.25) (thickness 0.04)) (justify mirror))
    )
    (fp_rect (start -0.925 0.47) (end 0.925 -0.47)
      (stroke (width 0.05) (type default)) (fill none) (layer "B.CrtYd"))
    (fp_rect (start -0.5 0.25) (end 0.5 -0.25)
      (stroke (width 0.15) (type solid)) (fill none) (layer "B.Fab"))
    (pad "1" smd roundrect (at -0.48 0 180) (size 0.59 0.64) (layers "B.Cu" "B.Paste" "B.Mask") (roundrect_rratio 0.25)
      (net 2 "VCC3V3") (pintype "passive"))
    (pad "2" smd roundrect (at 0.48 0 180) (size 0.59 0.64) (layers "B.Cu" "B.Paste" "B.Mask") (roundrect_rratio 0.25)
      (net 377 "MMC_RSTN") (pintype "passive"))
  )
)
